FILE_TYPE = MACRO_DRAWING;
SET COLOR_WIRE YELLOW;
SET COLOR_PROP ORANGE;
SET COLOR_DOT WHITE;
SET COLOR_ARC YELLOW;
SET COLOR_BODY GREEN;
SET COLOR_NOTE PURPLE;
SET PROP_DISPLAY VALUE;
SET PAGE_NUMBER P48;
SET PATH_NUMBER P56;
FORCEADD UNIVERSAL_GND..1
(-2225 3025);
FORCEPROP 3 LASTPIN (-2225 3075) SIG_NAME GND\g
J 0
(-2215 3085);
DISPLAY 0.659574 (-2215 3085);
PAINT MONO (-2215 3085);
DISPLAY INVISIBLE (-2215 3085);
FORCEPROP 1 LAST HDL_POWER GND
J 1
(-2200 2950);
DISPLAY 0.702128 (-2200 2950);
PAINT GREEN (-2200 2950);
DISPLAY INVISIBLE (-2200 2950);
FORCEPROP 2 LAST CDS_LIB logical_power
J 0
(-2225 3025);
DISPLAY INVISIBLE (-2225 3025);
FORCEPROP 1 LAST PATH I24
J 0
(-2150 3025);
DISPLAY 0.872340 (-2150 3025);
PAINT AQUA (-2150 3025);
DISPLAY INVISIBLE (-2150 3025);
FORCEADD VCCAUX15..1
(-2225 4125);
FORCEPROP 3 LASTPIN (-2225 4075) SIG_NAME P3V3_AUX\g
J 0
(-2215 4085);
DISPLAY 0.659574 (-2215 4085);
PAINT MONO (-2215 4085);
DISPLAY INVISIBLE (-2215 4085);
FORCEPROP 1 LAST HDL_POWER P3V3_AUX
J 1
(-2225 4175);
DISPLAY 0.702128 (-2225 4175);
PAINT GREEN (-2225 4175);
FORCEPROP 2 LAST CDS_LIB logical_power
J 0
(-2225 4125);
DISPLAY INVISIBLE (-2225 4125);
FORCEPROP 1 LAST PATH I25
J 0
(-2175 4150);
DISPLAY 0.872340 (-2175 4150);
PAINT AQUA (-2175 4150);
DISPLAY INVISIBLE (-2175 4150);
FORCEADD OFFPAGE..2
(-600 3625);
FORCEPROP 2 LAST $XR0 27 
J 0
(-411 3625);
DISPLAY 0.638298 (-411 3625);
PAINT MONO (-411 3625);
FORCEPROP 2 LAST CDS_LIB standard
J 0
(-600 3625);
DISPLAY INVISIBLE (-600 3625);
FORCEPROP 1 LAST OFFPAGE TRUE
J 0
(-275 3500);
DISPLAY 0.872340 (-275 3500);
PAINT GREEN (-275 3500);
DISPLAY INVISIBLE (-275 3500);
FORCEPROP 1 LAST COMMENT_BODY TRUE
J 0
(-645 3530);
DISPLAY 0.872340 (-645 3530);
PAINT PEACH (-645 3530);
DISPLAY INVISIBLE (-645 3530);
FORCEPROP 2 LAST PATH I31
J 0
(-400 3675);
DISPLAY 0.680851 (-400 3675);
DISPLAY INVISIBLE (-400 3675);
FORCEADD Q_RES..2
(-2225 3850);
FORCEPROP 1 LAST TOLERANCE 1%
J 0
(-2200 3850);
DISPLAY 0.510638 (-2200 3850);
PAINT SKYBLUE (-2200 3850);
FORCEPROP 1 LAST VALUE 4.7K
J 0
(-2200 3900);
DISPLAY 0.510638 (-2200 3900);
PAINT SKYBLUE (-2200 3900);
FORCEPROP 1 LAST WATTAGE 1/16W
J 0
(-2200 3800);
DISPLAY 0.510638 (-2200 3800);
PAINT SKYBLUE (-2200 3800);
FORCEPROP 1 LAST PACK_TYPE 0402LF
J 0
(-2200 3725);
DISPLAY 0.510638 (-2200 3725);
PAINT SKYBLUE (-2200 3725);
FORCEPROP 1 LAST MATERIAL EMPTY
J 0
(-2200 3750);
DISPLAY 0.510638 (-2200 3750);
PAINT RED (-2200 3750);
FORCEPROP 1 LAST PART_NUMBER CS24702FB10
J 0
(-2185 3725);
DISPLAY 0.510638 (-2185 3725);
PAINT WHITE (-2185 3725);
DISPLAY INVISIBLE (-2185 3725);
FORCEPROP 2 LAST CDS_LIB pure_quanta
J 0
(-2225 3850);
DISPLAY INVISIBLE (-2225 3850);
FORCEPROP 1 LAST PATH I33
J 0
(-2175 4025);
DISPLAY 0.978723 (-2175 4025);
PAINT WHITE (-2175 4025);
DISPLAY INVISIBLE (-2175 4025);
FORCEPROP 1 LAST $LOCATION R615
J 0
(-2180 3975);
DISPLAY 0.702128 (-2180 3975);
PAINT YELLOW (-2180 3975);
FORCEPROP 1 LASTPIN (-2225 3950) $PN 1
J 0
(-2220 3912);
DISPLAY 0.787234 (-2220 3912);
PAINT MONO (-2220 3912);
FORCEPROP 1 LASTPIN (-2225 3750) $PN 2
J 0
(-2220 3760);
DISPLAY 0.787234 (-2220 3760);
PAINT MONO (-2220 3760);
FORCEPROP 0 LAST CDS_LOCATION R615
J 0
(-2175 4025);
DISPLAY 0.680851 (-2175 4025);
DISPLAY INVISIBLE (-2175 4025);
FORCEPROP 0 LAST $SEC 1
J 0
(-2175 4025);
DISPLAY 0.680851 (-2175 4025);
PAINT MONO (-2175 4025);
DISPLAY INVISIBLE (-2175 4025);
FORCEPROP 0 LAST CDS_SEC 1
J 0
(-2175 4025);
DISPLAY 0.680851 (-2175 4025);
DISPLAY INVISIBLE (-2175 4025);
FORCEADD OFFPAGE..2
(-50 2000);
FORCEPROP 2 LAST $XR1 36 
J 0
(229 2000);
DISPLAY 0.638298 (229 2000);
PAINT MONO (229 2000);
FORCEPROP 2 LAST $XR0 13 
J 0
(139 2000);
DISPLAY 0.638298 (139 2000);
PAINT MONO (139 2000);
FORCEPROP 2 LAST CDS_LIB standard
J 0
(-50 2000);
DISPLAY INVISIBLE (-50 2000);
FORCEPROP 1 LAST OFFPAGE TRUE
J 0
(275 1875);
DISPLAY 0.872340 (275 1875);
PAINT GREEN (275 1875);
DISPLAY INVISIBLE (275 1875);
FORCEPROP 1 LAST COMMENT_BODY TRUE
J 0
(-95 1905);
DISPLAY 0.872340 (-95 1905);
PAINT PEACH (-95 1905);
DISPLAY INVISIBLE (-95 1905);
FORCEPROP 2 LAST PATH I37
J 0
(250 2050);
DISPLAY 0.680851 (250 2050);
DISPLAY INVISIBLE (250 2050);
FORCEADD UNIVERSAL_GND..1
R 2
(-375 1425);
FORCEPROP 3 LASTPIN (-375 1475) SIG_NAME GND\g
J 0
(-365 1485);
DISPLAY 0.659574 (-365 1485);
PAINT MONO (-365 1485);
DISPLAY INVISIBLE (-365 1485);
FORCEPROP 2 LAST CDS_LIB logical_power
J 0
(-375 1425);
DISPLAY INVISIBLE (-375 1425);
FORCEPROP 1 LAST HDL_POWER GND
J 1
(-400 1350);
DISPLAY 0.702128 (-400 1350);
PAINT GREEN (-400 1350);
DISPLAY INVISIBLE (-400 1350);
FORCEPROP 1 LAST PATH I38
J 2
(-450 1425);
DISPLAY 0.872340 (-450 1425);
PAINT AQUA (-450 1425);
DISPLAY INVISIBLE (-450 1425);
FORCEADD Q_RES..2
(-375 1750);
FORCEPROP 1 LAST PACK_TYPE 0402LF
J 0
(-335 1575);
DISPLAY 0.510638 (-335 1575);
PAINT SKYBLUE (-335 1575);
FORCEPROP 1 LAST PART_NUMBER CS41002FB09
J 0
(-335 1625);
DISPLAY 0.510638 (-335 1625);
PAINT WHITE (-335 1625);
FORCEPROP 1 LAST WATTAGE 1/16W
J 0
(-335 1725);
DISPLAY 0.510638 (-335 1725);
PAINT SKYBLUE (-335 1725);
FORCEPROP 1 LAST TOLERANCE 1%
J 0
(-330 1775);
DISPLAY 0.510638 (-330 1775);
PAINT SKYBLUE (-330 1775);
FORCEPROP 1 LAST VALUE 100K
J 0
(-330 1825);
DISPLAY 0.510638 (-330 1825);
PAINT SKYBLUE (-330 1825);
FORCEPROP 1 LAST MATERIAL CHIP
J 0
(-335 1675);
DISPLAY 0.510638 (-335 1675);
PAINT SKYBLUE (-335 1675);
FORCEPROP 2 LAST CDS_LIB pure_quanta
J 0
(-375 1750);
DISPLAY INVISIBLE (-375 1750);
FORCEPROP 1 LAST PATH I39
J 0
(-325 1925);
DISPLAY 0.978723 (-325 1925);
PAINT WHITE (-325 1925);
DISPLAY INVISIBLE (-325 1925);
FORCEPROP 1 LAST LOCATION R620
J 0
(-330 1875);
DISPLAY 0.702128 (-330 1875);
PAINT YELLOW (-330 1875);
FORCEPROP 0 LAST $SEC 1
J 0
(-325 1925);
DISPLAY 0.680851 (-325 1925);
PAINT MONO (-325 1925);
DISPLAY INVISIBLE (-325 1925);
FORCEPROP 0 LAST CDS_SEC 1
J 0
(-325 1925);
DISPLAY 1.021277 (-325 1925);
DISPLAY INVISIBLE (-325 1925);
FORCEPROP 1 LASTPIN (-375 1850) $PN 1
J 0
(-370 1812);
DISPLAY 0.808511 (-370 1812);
PAINT WHITE (-370 1812);
DISPLAY INVISIBLE (-370 1812);
FORCEPROP 1 LASTPIN (-375 1650) $PN 2
J 0
(-370 1660);
DISPLAY 0.808511 (-370 1660);
PAINT WHITE (-370 1660);
DISPLAY INVISIBLE (-370 1660);
FORCEADD Q_RES..1
R 6
(-1150 2000);
FORCEPROP 1 LAST VALUE 0
J 2
(-1000 1976);
DISPLAY 0.510638 (-1000 1976);
PAINT SKYBLUE (-1000 1976);
FORCEPROP 1 LAST MATERIAL CHIP
J 0
(-975 1950);
DISPLAY 0.510638 (-975 1950);
PAINT SKYBLUE (-975 1950);
FORCEPROP 1 LAST TOLERANCE 5%
J 0
(-1225 1876);
DISPLAY 0.510638 (-1225 1876);
PAINT SKYBLUE (-1225 1876);
DISPLAY INVISIBLE (-1225 1876);
FORCEPROP 2 LAST CDS_LIB pure_quanta
J 0
(-1150 1953);
DISPLAY INVISIBLE (-1150 1953);
FORCEPROP 1 LAST WATTAGE 1/16W
J 2
(-800 1876);
DISPLAY 0.510638 (-800 1876);
PAINT SKYBLUE (-800 1876);
DISPLAY INVISIBLE (-800 1876);
FORCEPROP 1 LAST PACK_TYPE 0402LF
J 0
(-1175 1926);
DISPLAY 0.510638 (-1175 1926);
PAINT SKYBLUE (-1175 1926);
DISPLAY INVISIBLE (-1175 1926);
FORCEPROP 1 LAST PART_NUMBER CS00002JB13
J 0
(-1250 1901);
DISPLAY 0.510638 (-1250 1901);
PAINT WHITE (-1250 1901);
DISPLAY INVISIBLE (-1250 1901);
FORCEPROP 1 LAST PATH I40
J 0
(-1200 1850);
DISPLAY 0.978723 (-1200 1850);
PAINT WHITE (-1200 1850);
DISPLAY INVISIBLE (-1200 1850);
FORCEPROP 1 LAST LOCATION R616
J 0
(-1350 1950);
DISPLAY 0.702128 (-1350 1950);
PAINT YELLOW (-1350 1950);
FORCEPROP 0 LAST $SEC 1
J 0
(-1375 1918);
DISPLAY 0.680851 (-1375 1918);
PAINT MONO (-1375 1918);
DISPLAY INVISIBLE (-1375 1918);
FORCEPROP 0 LAST CDS_SEC 1
J 0
(-1375 1902);
DISPLAY 1.021277 (-1375 1902);
DISPLAY INVISIBLE (-1375 1902);
FORCEPROP 1 LASTPIN (-1250 2000) $PN 1
J 0
(-1238 1950);
DISPLAY 0.808511 (-1238 1950);
PAINT WHITE (-1238 1950);
DISPLAY INVISIBLE (-1238 1950);
FORCEPROP 1 LASTPIN (-1050 2000) $PN 2
J 0
(-1088 1950);
DISPLAY 0.808511 (-1088 1950);
PAINT WHITE (-1088 1950);
DISPLAY INVISIBLE (-1088 1950);
FORCEADD VCCAUX15..1
(-2250 2575);
FORCEPROP 3 LASTPIN (-2250 2525) SIG_NAME P3V3_AUX\g
J 0
(-2240 2535);
DISPLAY 0.659574 (-2240 2535);
PAINT MONO (-2240 2535);
DISPLAY INVISIBLE (-2240 2535);
FORCEPROP 1 LAST HDL_POWER P3V3_AUX
J 1
(-2250 2625);
DISPLAY 0.702128 (-2250 2625);
PAINT GREEN (-2250 2625);
FORCEPROP 1 LAST PATH I41
J 0
(-2200 2600);
DISPLAY 0.872340 (-2200 2600);
PAINT AQUA (-2200 2600);
DISPLAY INVISIBLE (-2200 2600);
FORCEPROP 2 LAST CDS_LIB logical_power
J 0
(-2250 2575);
DISPLAY INVISIBLE (-2250 2575);
FORCEADD Q_RES..2
(-2250 2300);
FORCEPROP 1 LAST WATTAGE 1/16W
J 0
(-2225 2250);
DISPLAY 0.510638 (-2225 2250);
PAINT SKYBLUE (-2225 2250);
FORCEPROP 1 LAST MATERIAL EMPTY
J 0
(-2225 2200);
DISPLAY 0.510638 (-2225 2200);
PAINT RED (-2225 2200);
FORCEPROP 1 LAST PACK_TYPE 0402LF
J 0
(-2225 2175);
DISPLAY 0.510638 (-2225 2175);
PAINT SKYBLUE (-2225 2175);
FORCEPROP 1 LAST TOLERANCE 1%
J 0
(-2225 2300);
DISPLAY 0.510638 (-2225 2300);
PAINT SKYBLUE (-2225 2300);
FORCEPROP 1 LAST VALUE 4.7K
J 0
(-2225 2350);
DISPLAY 0.510638 (-2225 2350);
PAINT SKYBLUE (-2225 2350);
FORCEPROP 1 LAST PART_NUMBER CS24702FB10
J 0
(-2210 2175);
DISPLAY 0.510638 (-2210 2175);
PAINT WHITE (-2210 2175);
DISPLAY INVISIBLE (-2210 2175);
FORCEPROP 1 LAST PATH I42
J 0
(-2200 2475);
DISPLAY 0.978723 (-2200 2475);
PAINT WHITE (-2200 2475);
DISPLAY INVISIBLE (-2200 2475);
FORCEPROP 2 LAST CDS_LIB pure_quanta
J 0
(-2250 2300);
DISPLAY INVISIBLE (-2250 2300);
FORCEPROP 1 LAST $LOCATION R881
J 0
(-2205 2425);
DISPLAY 0.978723 (-2205 2425);
FORCEPROP 1 LASTPIN (-2250 2400) $PN 1
J 0
(-2245 2362);
DISPLAY 0.787234 (-2245 2362);
PAINT MONO (-2245 2362);
FORCEPROP 1 LASTPIN (-2250 2200) $PN 2
J 0
(-2245 2210);
DISPLAY 0.787234 (-2245 2210);
PAINT MONO (-2245 2210);
FORCEPROP 0 LAST CDS_LOCATION R881
J 0
(-2200 2475);
DISPLAY 0.680851 (-2200 2475);
DISPLAY INVISIBLE (-2200 2475);
FORCEPROP 0 LAST $SEC 1
J 0
(-2200 2475);
DISPLAY 0.680851 (-2200 2475);
PAINT MONO (-2200 2475);
DISPLAY INVISIBLE (-2200 2475);
FORCEPROP 0 LAST CDS_SEC 1
J 0
(-2200 2475);
DISPLAY 0.680851 (-2200 2475);
DISPLAY INVISIBLE (-2200 2475);
FORCEADD OFFPAGE..2
(50 250);
FORCEPROP 2 LAST $XR0 32 
J 0
(239 250);
DISPLAY 0.638298 (239 250);
PAINT MONO (239 250);
FORCEPROP 2 LAST $XR1 34 
J 0
(329 250);
DISPLAY 0.638298 (329 250);
PAINT MONO (329 250);
FORCEPROP 2 LAST CDS_LIB standard
J 0
(50 250);
DISPLAY INVISIBLE (50 250);
FORCEPROP 1 LAST OFFPAGE TRUE
J 0
(375 125);
DISPLAY 0.872340 (375 125);
PAINT GREEN (375 125);
DISPLAY INVISIBLE (375 125);
FORCEPROP 1 LAST COMMENT_BODY TRUE
J 0
(5 155);
DISPLAY 0.872340 (5 155);
PAINT PEACH (5 155);
DISPLAY INVISIBLE (5 155);
FORCEPROP 2 LAST PATH I45
J 0
(350 300);
DISPLAY 0.680851 (350 300);
DISPLAY INVISIBLE (350 300);
FORCEADD OFFPAGE..2
(50 400);
FORCEPROP 2 LAST $XR1 36 
J 0
(329 400);
DISPLAY 0.638298 (329 400);
PAINT MONO (329 400);
FORCEPROP 2 LAST $XR0 13 
J 0
(239 400);
DISPLAY 0.638298 (239 400);
PAINT MONO (239 400);
FORCEPROP 2 LAST CDS_LIB standard
J 0
(50 400);
DISPLAY INVISIBLE (50 400);
FORCEPROP 1 LAST OFFPAGE TRUE
J 0
(375 275);
DISPLAY 0.872340 (375 275);
PAINT GREEN (375 275);
DISPLAY INVISIBLE (375 275);
FORCEPROP 1 LAST COMMENT_BODY TRUE
J 0
(5 305);
DISPLAY 0.872340 (5 305);
PAINT PEACH (5 305);
DISPLAY INVISIBLE (5 305);
FORCEPROP 2 LAST PATH I46
J 0
(350 450);
DISPLAY 0.680851 (350 450);
DISPLAY INVISIBLE (350 450);
FORCEADD VCCAUX15..1
(-575 1025);
FORCEPROP 3 LASTPIN (-575 975) SIG_NAME P3V3_AUX\g
J 0
(-565 985);
DISPLAY 0.659574 (-565 985);
PAINT MONO (-565 985);
DISPLAY INVISIBLE (-565 985);
FORCEPROP 1 LAST HDL_POWER P3V3_AUX
J 1
(-575 1075);
DISPLAY 0.702128 (-575 1075);
PAINT GREEN (-575 1075);
FORCEPROP 2 LAST CDS_LIB logical_power
J 0
(-575 1025);
DISPLAY INVISIBLE (-575 1025);
FORCEPROP 1 LAST PATH I47
J 0
(-525 1050);
DISPLAY 0.872340 (-525 1050);
PAINT AQUA (-525 1050);
DISPLAY INVISIBLE (-525 1050);
FORCEADD Q_RES..2
(-575 800);
FORCEPROP 1 LAST VALUE 4.7K
J 0
(-525 875);
DISPLAY 0.510638 (-525 875);
PAINT SKYBLUE (-525 875);
FORCEPROP 1 LAST PACK_TYPE 0402LF
J 0
(-525 775);
DISPLAY 0.510638 (-525 775);
PAINT SKYBLUE (-525 775);
FORCEPROP 1 LAST WATTAGE 1/16W
J 0
(-525 725);
DISPLAY 0.510638 (-525 725);
PAINT SKYBLUE (-525 725);
FORCEPROP 1 LAST MATERIAL CHIP
J 0
(-525 675);
DISPLAY 0.510638 (-525 675);
PAINT SKYBLUE (-525 675);
FORCEPROP 1 LAST TOLERANCE 1%
J 0
(-525 825);
DISPLAY 0.510638 (-525 825);
PAINT SKYBLUE (-525 825);
FORCEPROP 2 LAST CDS_LIB pure_quanta
J 0
(-575 800);
DISPLAY INVISIBLE (-575 800);
FORCEPROP 1 LAST PART_NUMBER CS24702FB06
J 0
(-530 675);
DISPLAY 0.510638 (-530 675);
PAINT WHITE (-530 675);
DISPLAY INVISIBLE (-530 675);
FORCEPROP 1 LAST PATH I48
J 0
(-525 975);
DISPLAY 0.978723 (-525 975);
PAINT WHITE (-525 975);
DISPLAY INVISIBLE (-525 975);
FORCEPROP 1 LAST LOCATION R624
J 0
(-530 925);
DISPLAY 0.702128 (-530 925);
PAINT YELLOW (-530 925);
FORCEPROP 1 LASTPIN (-575 900) $PN 1
J 0
(-570 862);
DISPLAY 0.808511 (-570 862);
PAINT WHITE (-570 862);
FORCEPROP 1 LASTPIN (-575 700) $PN 2
J 0
(-570 710);
DISPLAY 0.808511 (-570 710);
PAINT WHITE (-570 710);
FORCEPROP 0 LAST $SEC 1
J 0
(-525 975);
DISPLAY 0.680851 (-525 975);
PAINT MONO (-525 975);
DISPLAY INVISIBLE (-525 975);
FORCEPROP 0 LAST CDS_SEC 1
J 0
(-525 975);
DISPLAY 0.680851 (-525 975);
DISPLAY INVISIBLE (-525 975);
FORCEADD VCCAUX15..1
(-1075 900);
FORCEPROP 3 LASTPIN (-1075 850) SIG_NAME P3V3_AUX\g
J 0
(-1065 860);
DISPLAY 0.659574 (-1065 860);
PAINT MONO (-1065 860);
DISPLAY INVISIBLE (-1065 860);
FORCEPROP 1 LAST HDL_POWER P3V3_AUX
J 1
(-1075 950);
DISPLAY 0.702128 (-1075 950);
PAINT GREEN (-1075 950);
FORCEPROP 2 LAST CDS_LIB logical_power
J 0
(-1075 900);
DISPLAY INVISIBLE (-1075 900);
FORCEPROP 1 LAST PATH I49
J 0
(-1025 925);
DISPLAY 0.872340 (-1025 925);
PAINT AQUA (-1025 925);
DISPLAY INVISIBLE (-1025 925);
FORCEADD Q_RES..1
(-950 250);
FORCEPROP 1 LAST MATERIAL CHIP
J 0
(-875 200);
DISPLAY 0.510638 (-875 200);
PAINT SKYBLUE (-875 200);
FORCEPROP 1 LAST VALUE 33.2
J 0
(-850 250);
DISPLAY 0.510638 (-850 250);
PAINT SKYBLUE (-850 250);
FORCEPROP 2 LAST CDS_LIB pure_quanta
J 0
(-950 250);
DISPLAY INVISIBLE (-950 250);
FORCEPROP 1 LAST WATTAGE 1/16W
J 2
(-975 100);
DISPLAY 0.510638 (-975 100);
PAINT SKYBLUE (-975 100);
DISPLAY INVISIBLE (-975 100);
FORCEPROP 1 LAST PACK_TYPE 0402LF
J 0
(-700 100);
DISPLAY 0.510638 (-700 100);
PAINT SKYBLUE (-700 100);
DISPLAY INVISIBLE (-700 100);
FORCEPROP 1 LAST PART_NUMBER CS03322FB03
J 0
(-1000 350);
DISPLAY 0.510638 (-1000 350);
PAINT WHITE (-1000 350);
DISPLAY INVISIBLE (-1000 350);
FORCEPROP 1 LAST TOLERANCE 1%
J 0
(-825 250);
DISPLAY 0.510638 (-825 250);
PAINT SKYBLUE (-825 250);
DISPLAY INVISIBLE (-825 250);
FORCEPROP 1 LAST PATH I50
J 0
(-1000 400);
DISPLAY 0.978723 (-1000 400);
PAINT WHITE (-1000 400);
DISPLAY INVISIBLE (-1000 400);
FORCEPROP 1 LAST LOCATION R509
J 0
(-1025 275);
DISPLAY 0.702128 (-1025 275);
PAINT YELLOW (-1025 275);
FORCEPROP 0 LAST $SEC 1
J 0
(-1125 300);
DISPLAY INVISIBLE (-1125 300);
FORCEPROP 0 LAST CDS_SEC 1
J 0
(-1125 300);
DISPLAY INVISIBLE (-1125 300);
FORCEPROP 1 LASTPIN (-1050 250) $PN 1
J 0
(-1038 262);
DISPLAY 0.808511 (-1038 262);
PAINT WHITE (-1038 262);
DISPLAY INVISIBLE (-1038 262);
FORCEPROP 1 LASTPIN (-850 250) $PN 2
J 0
(-888 262);
DISPLAY 0.808511 (-888 262);
PAINT WHITE (-888 262);
DISPLAY INVISIBLE (-888 262);
FORCEADD Q_RES..2
(-1075 675);
FORCEPROP 1 LAST VALUE 10K
J 0
(-1030 750);
DISPLAY 0.510638 (-1030 750);
PAINT SKYBLUE (-1030 750);
FORCEPROP 1 LAST TOLERANCE 1%
J 0
(-1030 700);
DISPLAY 0.510638 (-1030 700);
PAINT SKYBLUE (-1030 700);
FORCEPROP 1 LAST WATTAGE 1/16W
J 0
(-1035 650);
DISPLAY 0.510638 (-1035 650);
PAINT SKYBLUE (-1035 650);
FORCEPROP 1 LAST MATERIAL CHIP
J 0
(-1035 600);
DISPLAY 0.510638 (-1035 600);
PAINT SKYBLUE (-1035 600);
FORCEPROP 1 LAST PACK_TYPE 0402LF
J 0
(-1035 500);
DISPLAY 0.510638 (-1035 500);
PAINT SKYBLUE (-1035 500);
FORCEPROP 1 LAST PART_NUMBER CS31002FB08
J 0
(-1035 550);
DISPLAY 0.510638 (-1035 550);
PAINT WHITE (-1035 550);
FORCEPROP 2 LAST CDS_LIB pure_quanta
J 0
(-1075 675);
DISPLAY INVISIBLE (-1075 675);
FORCEPROP 1 LAST PATH I51
J 0
(-1025 850);
DISPLAY 0.978723 (-1025 850);
PAINT WHITE (-1025 850);
DISPLAY INVISIBLE (-1025 850);
FORCEPROP 1 LAST LOCATION R508
J 0
(-1030 800);
DISPLAY 0.702128 (-1030 800);
PAINT YELLOW (-1030 800);
FORCEPROP 0 LAST $SEC 1
J 0
(-1025 850);
DISPLAY 0.680851 (-1025 850);
PAINT MONO (-1025 850);
DISPLAY INVISIBLE (-1025 850);
FORCEPROP 0 LAST CDS_SEC 1
J 0
(-1025 850);
DISPLAY 1.021277 (-1025 850);
DISPLAY INVISIBLE (-1025 850);
FORCEPROP 1 LASTPIN (-1075 775) $PN 1
J 0
(-1070 737);
DISPLAY 0.808511 (-1070 737);
PAINT WHITE (-1070 737);
DISPLAY INVISIBLE (-1070 737);
FORCEPROP 1 LASTPIN (-1075 575) $PN 2
J 0
(-1070 585);
DISPLAY 0.808511 (-1070 585);
PAINT WHITE (-1070 585);
DISPLAY INVISIBLE (-1070 585);
FORCEADD Q_RES..2
(-2050 -75);
FORCEPROP 1 LAST TOLERANCE 1%
J 0
(-2000 -100);
DISPLAY 0.510638 (-2000 -100);
PAINT SKYBLUE (-2000 -100);
FORCEPROP 1 LAST VALUE 100
J 0
(-2000 -50);
DISPLAY 0.510638 (-2000 -50);
PAINT SKYBLUE (-2000 -50);
FORCEPROP 1 LAST MATERIAL EMPTY
J 0
(-2000 -150);
DISPLAY 0.510638 (-2000 -150);
PAINT RED (-2000 -150);
FORCEPROP 1 LAST PACK_TYPE 0402LF
J 0
(-2000 -250);
DISPLAY 0.510638 (-2000 -250);
PAINT SKYBLUE (-2000 -250);
FORCEPROP 1 LAST PART_NUMBER CS11002FB07
J 0
(-2000 -200);
DISPLAY 0.510638 (-2000 -200);
PAINT WHITE (-2000 -200);
FORCEPROP 1 LAST PATH I52
J 0
(-2000 100);
DISPLAY 0.978723 (-2000 100);
PAINT WHITE (-2000 100);
DISPLAY INVISIBLE (-2000 100);
FORCEPROP 2 LAST CDS_LIB pure_quanta
J 0
(-2050 -75);
DISPLAY INVISIBLE (-2050 -75);
FORCEPROP 1 LAST WATTAGE 1/16W
J 0
(-2010 -100);
DISPLAY 0.510638 (-2010 -100);
PAINT SKYBLUE (-2010 -100);
DISPLAY INVISIBLE (-2010 -100);
FORCEPROP 1 LAST LOCATION R507
J 0
(-2000 0);
DISPLAY 0.702128 (-2000 0);
PAINT YELLOW (-2000 0);
FORCEPROP 1 LASTPIN (-2050 25) $PN 1
J 0
(-2045 -13);
DISPLAY 0.808511 (-2045 -13);
PAINT WHITE (-2045 -13);
FORCEPROP 1 LASTPIN (-2050 -175) $PN 2
J 0
(-2045 -165);
DISPLAY 0.808511 (-2045 -165);
PAINT WHITE (-2045 -165);
FORCEPROP 0 LAST $SEC 1
J 0
(-2025 100);
DISPLAY 0.680851 (-2025 100);
PAINT MONO (-2025 100);
DISPLAY INVISIBLE (-2025 100);
FORCEPROP 0 LAST CDS_SEC 1
J 0
(-2025 100);
DISPLAY 0.680851 (-2025 100);
DISPLAY INVISIBLE (-2025 100);
FORCEADD Q_RES..2
(-2675 -50);
FORCEPROP 1 LAST PACK_TYPE 0402LF
J 0
(-2625 -225);
DISPLAY 0.510638 (-2625 -225);
PAINT SKYBLUE (-2625 -225);
FORCEPROP 1 LAST TOLERANCE 1%
J 0
(-2625 -75);
DISPLAY 0.510638 (-2625 -75);
PAINT SKYBLUE (-2625 -75);
FORCEPROP 1 LAST VALUE 100
J 0
(-2625 -25);
DISPLAY 0.510638 (-2625 -25);
PAINT SKYBLUE (-2625 -25);
FORCEPROP 1 LAST PART_NUMBER CS11002FB07
J 0
(-2625 -175);
DISPLAY 0.510638 (-2625 -175);
PAINT WHITE (-2625 -175);
FORCEPROP 1 LAST MATERIAL EMPTY
J 0
(-2625 -125);
DISPLAY 0.510638 (-2625 -125);
PAINT RED (-2625 -125);
FORCEPROP 1 LAST PATH I53
J 0
(-2625 125);
DISPLAY 0.978723 (-2625 125);
PAINT WHITE (-2625 125);
DISPLAY INVISIBLE (-2625 125);
FORCEPROP 1 LAST WATTAGE 1/16W
J 0
(-2635 -75);
DISPLAY 0.510638 (-2635 -75);
PAINT SKYBLUE (-2635 -75);
DISPLAY INVISIBLE (-2635 -75);
FORCEPROP 2 LAST CDS_LIB pure_quanta
J 0
(-2675 -50);
DISPLAY INVISIBLE (-2675 -50);
FORCEPROP 1 LAST LOCATION R506
J 0
(-2625 25);
DISPLAY 0.702128 (-2625 25);
PAINT YELLOW (-2625 25);
FORCEPROP 1 LASTPIN (-2675 50) $PN 1
J 0
(-2670 12);
DISPLAY 0.808511 (-2670 12);
PAINT WHITE (-2670 12);
FORCEPROP 1 LASTPIN (-2675 -150) $PN 2
J 0
(-2670 -140);
DISPLAY 0.808511 (-2670 -140);
PAINT WHITE (-2670 -140);
FORCEPROP 0 LAST $SEC 1
J 0
(-2650 125);
DISPLAY 0.680851 (-2650 125);
PAINT MONO (-2650 125);
DISPLAY INVISIBLE (-2650 125);
FORCEPROP 0 LAST CDS_SEC 1
J 0
(-2650 125);
DISPLAY 0.680851 (-2650 125);
DISPLAY INVISIBLE (-2650 125);
FORCEADD UNIVERSAL_GND..1
R 2
(-2050 -225);
FORCEPROP 3 LASTPIN (-2050 -175) SIG_NAME GND\g
J 0
(-2040 -165);
DISPLAY 0.659574 (-2040 -165);
PAINT MONO (-2040 -165);
DISPLAY INVISIBLE (-2040 -165);
FORCEPROP 1 LAST HDL_POWER GND
J 1
(-2075 -300);
DISPLAY 0.702128 (-2075 -300);
PAINT GREEN (-2075 -300);
DISPLAY INVISIBLE (-2075 -300);
FORCEPROP 2 LAST CDS_LIB logical_power
J 0
(-2050 -225);
DISPLAY INVISIBLE (-2050 -225);
FORCEPROP 1 LAST PATH I54
J 2
(-2125 -225);
DISPLAY 0.872340 (-2125 -225);
PAINT AQUA (-2125 -225);
DISPLAY INVISIBLE (-2125 -225);
FORCEADD UNIVERSAL_GND..1
R 2
(-2675 -225);
FORCEPROP 3 LASTPIN (-2675 -175) SIG_NAME GND\g
J 0
(-2665 -165);
DISPLAY 0.659574 (-2665 -165);
PAINT MONO (-2665 -165);
DISPLAY INVISIBLE (-2665 -165);
FORCEPROP 1 LAST PATH I55
J 2
(-2750 -225);
DISPLAY 0.872340 (-2750 -225);
PAINT AQUA (-2750 -225);
DISPLAY INVISIBLE (-2750 -225);
FORCEPROP 1 LAST HDL_POWER GND
J 1
(-2700 -300);
DISPLAY 0.702128 (-2700 -300);
PAINT GREEN (-2700 -300);
DISPLAY INVISIBLE (-2700 -300);
FORCEPROP 2 LAST CDS_LIB logical_power
J 0
(-2675 -225);
DISPLAY INVISIBLE (-2675 -225);
FORCEADD Q_RES..2
(-2225 3300);
FORCEPROP 1 LAST VALUE 100
J 0
(-2180 3375);
DISPLAY 0.510638 (-2180 3375);
PAINT SKYBLUE (-2180 3375);
FORCEPROP 1 LAST TOLERANCE 1%
J 0
(-2180 3325);
DISPLAY 0.510638 (-2180 3325);
PAINT SKYBLUE (-2180 3325);
FORCEPROP 1 LAST WATTAGE 1/16W
J 0
(-2185 3275);
DISPLAY 0.510638 (-2185 3275);
PAINT SKYBLUE (-2185 3275);
FORCEPROP 1 LAST PART_NUMBER CS11002FB07
J 0
(-2185 3175);
DISPLAY 0.510638 (-2185 3175);
PAINT WHITE (-2185 3175);
FORCEPROP 1 LAST PACK_TYPE 0402LF
J 0
(-2185 3125);
DISPLAY 0.510638 (-2185 3125);
PAINT SKYBLUE (-2185 3125);
FORCEPROP 1 LAST MATERIAL EMPTY
J 0
(-2185 3225);
DISPLAY 0.510638 (-2185 3225);
PAINT RED (-2185 3225);
FORCEPROP 2 LAST CDS_LIB pure_quanta
J 0
(-2225 3300);
DISPLAY INVISIBLE (-2225 3300);
FORCEPROP 1 LAST PATH I56
J 0
(-2175 3475);
DISPLAY 0.978723 (-2175 3475);
PAINT WHITE (-2175 3475);
DISPLAY INVISIBLE (-2175 3475);
FORCEPROP 1 LAST LOCATION R431
J 0
(-2180 3425);
DISPLAY 0.702128 (-2180 3425);
PAINT YELLOW (-2180 3425);
FORCEPROP 1 LASTPIN (-2225 3400) $PN 1
J 0
(-2220 3362);
DISPLAY 0.787234 (-2220 3362);
PAINT MONO (-2220 3362);
FORCEPROP 1 LASTPIN (-2225 3200) $PN 2
J 0
(-2220 3210);
DISPLAY 0.787234 (-2220 3210);
PAINT MONO (-2220 3210);
FORCEPROP 0 LAST $SEC 1
J 0
(-2175 3475);
DISPLAY 0.680851 (-2175 3475);
PAINT MONO (-2175 3475);
DISPLAY INVISIBLE (-2175 3475);
FORCEPROP 0 LAST CDS_SEC 1
J 0
(-2175 3475);
DISPLAY 0.680851 (-2175 3475);
DISPLAY INVISIBLE (-2175 3475);
FORCEADD QUANTA_TITLE_BLOCK_C..1
(6150 -1925);
FORCEPROP 0 LAST CDS_CON_LAST_MODIFIED Fri Aug 25 17:25:47 2023
J 0
(4265 -1910);
DISPLAY INVISIBLE (4265 -1910);
FORCEPROP 2 LAST Q_DEPT 
J 1
(2387 -1876);
DISPLAY 1.957447 (2387 -1876);
PAINT GREEN (2387 -1876);
FORCEPROP 1 LAST CUSTOM_TXT_CDS <CON_LAST_MODIFIED>
J 0
(4265 -1910);
DISPLAY 0.978723 (4265 -1910);
FORCEPROP 2 LAST CUSTOM_TXT_CDS <XR_PAGE_TITLE>
J 0
(-1740 3325);
DISPLAY 0.638298 (-1740 3325);
PAINT PINK (-1740 3325);
DISPLAY INVISIBLE (-1740 3325);
FORCEPROP 1 LAST CUSTOM_TXT_CDS <NAME_2>
J 0
(2975 -1875);
FORCEPROP 1 LAST CUSTOM_TXT_CDS <NAME_1>
J 0
(2975 -1750);
FORCEPROP 1 LAST CUSTOM_TXT_CDS <Q_NUMBER>
J 0
(4747 -1822);
DISPLAY 1.212766 (4747 -1822);
FORCEPROP 1 LAST CUSTOM_TXT_CDS <Q_PROJ>
J 0
(3768 -1823);
DISPLAY 1.212766 (3768 -1823);
FORCEPROP 1 LAST CUSTOM_TXT_CDS <Q_REV>
J 0
(5966 -1822);
DISPLAY 1.212766 (5966 -1822);
FORCEPROP 1 LAST CUSTOM_TXT_CDS <CON_PAGE_NUM> OF <CON_TOTAL_PAGES>
J 0
(5704 -1907);
DISPLAY 0.978723 (5704 -1907);
FORCEPROP 1 LAST Q_TITLE DEBUG HEADERS(SWITCH)
J 0
(-3116 -1824);
DISPLAY 2.446809 (-3116 -1824);
PAINT GREEN (-3116 -1824);
FORCEPROP 1 LAST COMMENT_BODY TRUE
J 0
(6162 -1938);
DISPLAY 0.978723 (6162 -1938);
PAINT PEACH (6162 -1938);
DISPLAY INVISIBLE (6162 -1938);
FORCEPROP 1 LAST CDS_LMAN_SYM_OUTLINE -9475,6775,100,-125
J 0
(6150 -1925);
DISPLAY 0.468085 (6150 -1925);
PAINT GREEN (6150 -1925);
DISPLAY INVISIBLE (6150 -1925);
FORCEPROP 2 LAST CDS_LIB pure_quanta
J 0
(6150 -1925);
DISPLAY INVISIBLE (6150 -1925);
FORCEPROP 2 LAST PAGE_BORDER TRUE
J 0
(-1740 3325);
DISPLAY 0.638298 (-1740 3325);
PAINT PINK (-1740 3325);
DISPLAY INVISIBLE (-1740 3325);
FORCEPROP 2 LAST CDS_XR_PAGE_TITLE CR-48 : @SCM_LIB.SCM(SCH_1):PAGE48
J 0
(-1740 3325);
DISPLAY 0.638298 (-1740 3325);
PAINT PINK (-1740 3325);
DISPLAY INVISIBLE (-1740 3325);
FORCEADD DNS..1
(-2075 -50);
PAINT RED (-2075 -50);
FORCEPROP 1 LAST COMMENT_BODY TRUE
R 1
J 0
(-2000 -275);
DISPLAY 0.872340 (-2000 -275);
PAINT PEACH (-2000 -275);
DISPLAY INVISIBLE (-2000 -275);
FORCEPROP 2 LAST CDS_LIB mstr_misc
J 0
(-2075 -50);
DISPLAY INVISIBLE (-2075 -50);
FORCEADD DNS..1
(-2675 -25);
PAINT RED (-2675 -25);
FORCEPROP 2 LAST CDS_LIB mstr_misc
J 0
(-2675 -25);
DISPLAY INVISIBLE (-2675 -25);
FORCEPROP 1 LAST COMMENT_BODY TRUE
R 1
J 0
(-2600 -250);
DISPLAY 0.872340 (-2600 -250);
PAINT PEACH (-2600 -250);
DISPLAY INVISIBLE (-2600 -250);
FORCEADD DNS..1
(-2250 2275);
PAINT RED (-2250 2275);
FORCEPROP 1 LAST COMMENT_BODY TRUE
R 1
J 0
(-2175 2050);
DISPLAY 0.872340 (-2175 2050);
PAINT PEACH (-2175 2050);
DISPLAY INVISIBLE (-2175 2050);
FORCEPROP 2 LAST CDS_LIB mstr_misc
J 0
(-2250 2275);
DISPLAY INVISIBLE (-2250 2275);
FORCEADD DNS..1
(-2225 3825);
PAINT RED (-2225 3825);
FORCEPROP 1 LAST COMMENT_BODY TRUE
R 1
J 0
(-2150 3600);
DISPLAY 0.872340 (-2150 3600);
PAINT PEACH (-2150 3600);
DISPLAY INVISIBLE (-2150 3600);
FORCEPROP 2 LAST CDS_LIB mstr_misc
J 0
(-2225 3825);
DISPLAY INVISIBLE (-2225 3825);
FORCEADD DNS..1
(-2225 3250);
PAINT RED (-2225 3250);
FORCEPROP 1 LAST COMMENT_BODY TRUE
R 1
J 0
(-2150 3025);
DISPLAY 0.872340 (-2150 3025);
PAINT PEACH (-2150 3025);
DISPLAY INVISIBLE (-2150 3025);
FORCEPROP 2 LAST CDS_LIB mstr_misc
J 0
(-2225 3250);
DISPLAY INVISIBLE (-2225 3250);
WIRE 16 -1 (-575 975)(-575 900);
WIRE 16 -1 (-2225 4075)(-2225 3950);
WIRE 16 -1 (-2250 2525)(-2250 2400);
WIRE 16 -1 (-1075 850)(-1075 775);
WIRE 16 -1 (-2675 -175)(-2675 -150);
WIRE 16 -1 (-375 1475)(-375 1650);
WIRE 16 -1 (-2225 3075)(-2225 3200);
WIRE 16 -1 (0 250)(-850 250);
FORCEPROP 2 LAST SIG_NAME JTAG_SCM_PLD_JTAGEN
J 2
(15 260);
DISPLAY 0.808511 (15 260);
WIRE 16 -1 (-575 700)(-575 400);
WIRE 16 -1 (0 400)(-575 400);
WIRE 16 -1 (-2675 400)(-2675 50);
WIRE 16 -1 (-2675 400)(-575 400);
FORCEPROP 2 LAST SIG_NAME FM_BMC_DEBUG_SW_N
J 0
(-1835 410);
DISPLAY 0.808511 (-1835 410);
WIRE 16 -1 (-2050 250)(-2050 25);
WIRE 16 -1 (-1050 250)(-1075 250);
WIRE 16 -1 (-1075 575)(-1075 250);
WIRE 16 -1 (-1075 250)(-2050 250);
FORCEPROP 2 LAST SIG_NAME MB_JTAG_PLD_R_JTAGEN
J 2
(-1135 260);
DISPLAY 0.808511 (-1135 260);
WIRE 16 -1 (-2250 2000)(-2250 2200);
WIRE 16 -1 (-1250 2000)(-2250 2000);
FORCEPROP 0 LAST SIG_NAME FM_JTAG_TCK_MUX_BMC_SEL_R
J 0
(-2160 2010);
DISPLAY 0.808511 (-2160 2010);
WIRE 16 -1 (-375 2000)(-1050 2000);
FORCEPROP 2 LAST SIG_NAME FM_JTAG_TCK_MUX_BMC_SEL
J 0
(-960 2010);
DISPLAY 0.808511 (-960 2010);
WIRE 16 -1 (-375 1850)(-375 2000);
WIRE 16 -1 (-100 2000)(-375 2000);
WIRE 16 -1 (-2225 3625)(-2225 3400);
WIRE 16 -1 (-2225 3750)(-2225 3625);
WIRE 16 -1 (-650 3625)(-2225 3625);
FORCEPROP 0 LAST SIG_NAME FM_BMC_DISABLE
J 0
(-1260 3635);
DISPLAY 0.808511 (-1260 3635);
DOT 1 (-2225 3625);
DOT 1 (-1075 250);
DOT 1 (-575 400);
DOT 1 (-375 2000);
FORCENOTE
FM_BMC_DISABLE : BMC DISABLE
(-125 3825) 0;
DISPLAY LEFT (-125 3825);
DISPLAY 1.595745 (-125 3825);
PAINT RED (-125 3825);
FORCENOTE
GND : DISABLE BMC
(-125 3700) 0;
DISPLAY LEFT (-125 3700);
DISPLAY 1.595745 (-125 3700);
PAINT RED (-125 3700);
FORCENOTE
FLOAT : ENABLE BMC(DEFAULT)
(-125 3575) 0;
DISPLAY LEFT (-125 3575);
DISPLAY 1.595745 (-125 3575);
PAINT RED (-125 3575);
FORCENOTE
FM_JTAG_TCK_MUX_BMC_SEL_R : JTAG TCK SEL
(525 2100) 0;
DISPLAY LEFT (525 2100);
DISPLAY 1.595745 (525 2100);
PAINT RED (525 2100);
FORCENOTE
VCC : TCK TO PCH
(525 1975) 0;
DISPLAY LEFT (525 1975);
DISPLAY 1.595745 (525 1975);
PAINT RED (525 1975);
FORCENOTE
GND : TCK TO CPU(DEFAULT)
(525 1850) 0;
DISPLAY LEFT (525 1850);
DISPLAY 1.595745 (525 1850);
PAINT RED (525 1850);
FORCENOTE
FM_BMC_DEBUG_SW_N : BMC/BIOS DEBUG SWITCH
(550 800) 0;
DISPLAY LEFT (550 800);
DISPLAY 1.595745 (550 800);
PAINT RED (550 800);
FORCENOTE
GND : BMC DEBUG
(550 675) 0;
DISPLAY LEFT (550 675);
DISPLAY 1.595745 (550 675);
PAINT RED (550 675);
FORCENOTE
VCC : (DEFAULT)
(550 550) 0;
DISPLAY LEFT (550 550);
DISPLAY 1.595745 (550 550);
PAINT RED (550 550);
FORCENOTE
MB_JTAG_PLD_R_JTAGEN : JTAGEN
(550 50) 0;
DISPLAY LEFT (550 50);
DISPLAY 1.595745 (550 50);
PAINT RED (550 50);
FORCENOTE
GND : DISABLE PROGRAMING
(550 -75) 0;
DISPLAY LEFT (550 -75);
DISPLAY 1.595745 (550 -75);
PAINT RED (550 -75);
FORCENOTE
VCC : ENABLE PROGRAMING(DEFAULT)
(550 -200) 0;
DISPLAY LEFT (550 -200);
DISPLAY 1.595745 (550 -200);
PAINT RED (550 -200);
QUIT
